# BASEBOARD_FAB2 (Tioga Pass) — schematic netlist excerpt (pin names and nets, part order shuffled) for the footprints in the layout excerpt that follows; sources: Cadence DE-HDL packaged netlist, KiCad conversion of Wiwynn_Tioga_Pass_MB.brd

EU1G1  IR354XX  IR35411 IC  pkg SM  page 224
  VOS  = PVDDQ_GHJ
  LGND  = GND
  VCC  = VR_PVDDQ_GHJ_PH1_VCIN
  VDRV  = P5V_STBY
  PGND(0)  = GND
  GL(0)  = TP_PVDDQ_GHJ_PH1_GL_0
  PGND(1)  = GND
  SW  = VR_PVDDQ_GHJ_PH1_SW
  VIN(0)  = VR_FET_SW_P12V_STBY_PVDDQ_GHJ
  VIN(1)  = VR_FET_SW_P12V_STBY_PVDDQ_GHJ
  NC  = NC
  PHASE  = VR_PVDDQ_GHJ_PH1_PHASE
  BOOST  = VR_PVDDQ_GHJ_PH1_BOOT_R
  PWM  = VR_PVDDQ_GHJ_PWM1
  EN  = P5V_STBY
  TOUT_FLT  = A_TSENSE_PVDDQ_GHJ
  OCSET  = VR_PVDDQ_GHJ_PH1_OCSET
  IOUT  = ISENSE_PVDDQ_GHJ_PH1_IMON
  REFIN  = VR_PVDDQ_GHJ_AIREF1
  PGND(2)  = GND
  GL(1)  = TP_PVDDQ_GHJ_PH1_GL_1

(kicad_pcb
	(version 20260206)
	(generator "pcbnew")
	(generator_version "10.0")
	(general
		(thickness 1.6)
		(legacy_teardrops no)
	)
	(paper "A4")
	(title_block
		(title "Wiwynn_Tioga_Pass_MB.brd")
		(comment 1 "Tioga Pass / footprints 2251-2251 of 4770")
	)
	(layers
		(0 "F.Cu" signal "TOP")
		(4 "In1.Cu" signal "L2GND")
		(6 "In2.Cu" signal "L3")
		(8 "In3.Cu" signal "L4GND")
		(10 "In4.Cu" signal "L5")
		(12 "In5.Cu" signal "L6GND")
		(14 "In6.Cu" signal "L7VCC")
		(16 "In7.Cu" signal "L8VCC")
		(18 "In8.Cu" signal "L9GND")
		(20 "In9.Cu" signal "L10")
		(22 "In10.Cu" signal "L11GND")
		(24 "In11.Cu" signal "L12")
		(26 "In12.Cu" signal "L13GND")
		(2 "B.Cu" signal "BOTTOM")
		(9 "F.Adhes" user "F.Adhesive")
		(11 "B.Adhes" user "B.Adhesive")
		(13 "F.Paste" user "Package Geometry/Pastemask Top")
		(15 "B.Paste" user "Package Geometry/Pastemask Bottom")
		(5 "F.SilkS" user "Ref Des/Silkscreen Top")
		(7 "B.SilkS" user "Ref Des/Silkscreen Bottom")
		(1 "F.Mask" user "Board Geometry/Soldermask Top")
		(3 "B.Mask" user "Board Geometry/Soldermask Bottom")
		(17 "Dwgs.User" user "User.Drawings")
		(19 "Cmts.User" user "User.Comments")
		(21 "Eco1.User" user "User.Eco1")
		(23 "Eco2.User" user "User.Eco2")
		(25 "Edge.Cuts" user "Board Geometry/Outline")
		(27 "Margin" user)
		(31 "F.CrtYd" user "Package Geometry/Place Bound Top")
		(29 "B.CrtYd" user "Package Geometry/Place Bound Bottom")
		(35 "F.Fab" user "Ref Des/Assembly Top")
		(33 "B.Fab" user "Ref Des/Assembly Bottom")
	)
	(footprint ""
		(layer "F.Cu")
		(at 4.962906 -9.493758 90)
		(property "Reference" "EU1G1"
			(at -1.289558 -4.047236 90)
			(unlocked yes)
			(layer "F.SilkS")
			(effects
				(font
					(size 0.7874 0.5842)
					(thickness 0.1524)
				)
			)
		)
		(property "Value" ""
			(at 0 0 90)
			(layer "F.Fab")
			(effects
				(font
					(size 1.27 1.27)
				)
			)
		)
		(duplicate_pad_numbers_are_jumpers no)
		(fp_line
			(start 2.9718 -3.5052)
			(end 2.9718 3.429)
			(stroke
				(width 0.1524)
				(type default)
			)
			(layer "F.SilkS")
		)
		(fp_line
			(start -3.0099 -3.5052)
			(end 2.9718 -3.5052)
			(stroke
				(width 0.1524)
				(type default)
			)
			(layer "F.SilkS")
		)
		(fp_line
			(start 2.9718 3.429)
			(end -3.0099 3.429)
			(stroke
				(width 0.1524)
				(type default)
			)
			(layer "F.SilkS")
		)
		(fp_line
			(start -3.0099 3.429)
			(end -3.0099 -3.5052)
			(stroke
				(width 0.1524)
				(type default)
			)
			(layer "F.SilkS")
		)
		(fp_circle
			(center -3.057398 -2.678684)
			(end -3.057398 -2.551684)
			(stroke
				(width 0.254)
				(type default)
			)
			(fill no)
			(layer "F.SilkS")
		)
		(fp_poly
			(pts
				(xy -2.9972 -3.4925) (xy -2.9972 -2.6924) (xy -2.1971 -3.4925)
			)
			(stroke
				(width 0)
				(type default)
			)
			(fill yes)
			(layer "F.SilkS")
		)
		(fp_poly
			(pts
				(xy -2.549906 -3.050032) (xy -2.549906 3.050032) (xy 2.549906 3.050032) (xy 2.549906 -3.050032)
			)
			(stroke
				(width 0)
				(type default)
			)
			(fill no)
			(layer "F.CrtYd")
		)
		(fp_line
			(start 2.549906 -3.050032)
			(end 2.549906 3.050032)
			(stroke
				(width 0.1)
				(type default)
			)
			(layer "F.Fab")
		)
		(fp_line
			(start -2.549906 -3.050032)
			(end 2.549906 -3.050032)
			(stroke
				(width 0.1)
				(type default)
			)
			(layer "F.Fab")
		)
		(fp_line
			(start 2.549906 3.050032)
			(end -2.549906 3.050032)
			(stroke
				(width 0.1)
				(type default)
			)
			(layer "F.Fab")
		)
		(fp_line
			(start -2.549906 3.050032)
			(end -2.549906 -3.050032)
			(stroke
				(width 0.1)
				(type default)
			)
			(layer "F.Fab")
		)
		(fp_circle
			(center -3.057398 -2.678684)
			(end -3.057398 -2.551684)
			(stroke
				(width 0.254)
				(type default)
			)
			(fill no)
			(layer "F.Fab")
		)
		(pad "1" smd rect
			(at -2.39522 -2.279904 90)
			(size 0.7112 0.254)
			(layers "F.Cu" "F.Mask" "F.Paste")
			(net "PVDDQ_GHJ")
		)
		(pad "2" smd rect
			(at -2.39522 -1.83007 90)
			(size 0.7112 0.254)
			(layers "F.Cu" "F.Mask" "F.Paste")
			(net "GND")
		)
		(pad "3" smd rect
			(at -2.39522 -1.379982 90)
			(size 0.7112 0.254)
			(layers "F.Cu" "F.Mask" "F.Paste")
			(net "VR_PVDDQ_GHJ_PH1_VCIN")
		)
		(pad "4" smd rect
			(at -2.39522 -0.929894 90)
			(size 0.7112 0.254)
			(layers "F.Cu" "F.Mask" "F.Paste")
			(net "P5V_STBY")
		)
		(pad "5" smd rect
			(at -2.39522 -0.48006 90)
			(size 0.7112 0.254)
			(layers "F.Cu" "F.Mask" "F.Paste")
			(net "GND")
		)
		(pad "6" smd rect
			(at -2.39522 -0.029972 90)
			(size 0.7112 0.254)
			(layers "F.Cu" "F.Mask" "F.Paste")
			(net "TP_PVDDQ_GHJ_PH1_GL_0")
		)
		(pad "7" smd custom
			(at 0.016764 1.145032 90)
			(size 0.53975 0.53975)
			(layers "F.Cu" "F.Mask" "F.Paste")
			(net "GND")
			(options
				(clearance outline)
				(anchor circle)
			)
			(primitives
				(gr_poly
					(pts
						(xy -2.7051 1.0795) (xy -2.7051 -0.3683) (xy -0.9271 -0.3683) (xy -0.9271 -1.0795) (xy 2.7051 -1.0795)
						(xy 2.7051 1.0795)
					)
					(width 0)
					(fill yes)
				)
			)
		)
		(pad "10" smd rect
			(at -0.008382 2.874772 90)
			(size 4.3434 0.6096)
			(layers "F.Cu" "F.Mask" "F.Paste")
			(net "VR_PVDDQ_GHJ_PH1_SW")
		)
		(pad "25" smd rect
			(at 1.548384 -1.283208 90)
			(size 2.3368 2.0066)
			(layers "F.Cu" "F.Mask" "F.Paste")
			(net "VR_FET_SW_P12V_STBY_PVDDQ_GHJ")
		)
		(pad "30" smd rect
			(at 2.050034 -2.895092 90)
			(size 0.254 0.7112)
			(layers "F.Cu" "F.Mask" "F.Paste")
			(net "VR_FET_SW_P12V_STBY_PVDDQ_GHJ")
		)
		(pad "31" smd rect
			(at 1.599946 -2.895092 90)
			(size 0.254 0.7112)
			(layers "F.Cu" "F.Mask" "F.Paste")
			(net "Net_296")
		)
		(pad "32" smd rect
			(at 1.150112 -2.895092 90)
			(size 0.254 0.7112)
			(layers "F.Cu" "F.Mask" "F.Paste")
			(net "VR_PVDDQ_GHJ_PH1_PHASE")
		)
		(pad "33" smd rect
			(at 0.700024 -2.895092 90)
			(size 0.254 0.7112)
			(layers "F.Cu" "F.Mask" "F.Paste")
			(net "VR_PVDDQ_GHJ_PH1_BOOT_R")
		)
		(pad "34" smd rect
			(at 0.249936 -2.895092 90)
			(size 0.254 0.7112)
			(layers "F.Cu" "F.Mask" "F.Paste")
			(net "VR_PVDDQ_GHJ_PWM1")
		)
		(pad "35" smd rect
			(at -0.199898 -2.895092 90)
			(size 0.254 0.7112)
			(layers "F.Cu" "F.Mask" "F.Paste")
			(net "P5V_STBY")
		)
		(pad "36" smd rect
			(at -0.649986 -2.895092 90)
			(size 0.254 0.7112)
			(layers "F.Cu" "F.Mask" "F.Paste")
			(net "A_TSENSE_PVDDQ_GHJ")
		)
		(pad "37" smd rect
			(at -1.100074 -2.895092 90)
			(size 0.254 0.7112)
			(layers "F.Cu" "F.Mask" "F.Paste")
			(net "VR_PVDDQ_GHJ_PH1_OCSET")
		)
		(pad "38" smd rect
			(at -1.549908 -2.895092 90)
			(size 0.254 0.7112)
			(layers "F.Cu" "F.Mask" "F.Paste")
			(net "ISENSE_PVDDQ_GHJ_PH1_IMON")
		)
		(pad "39" smd rect
			(at -1.999996 -2.895092 90)
			(size 0.254 0.7112)
			(layers "F.Cu" "F.Mask" "F.Paste")
			(net "VR_PVDDQ_GHJ_AIREF1")
		)
		(pad "40" smd rect
			(at -0.871728 -1.283208 90)
			(size 1.8034 2.0066)
			(layers "F.Cu" "F.Mask" "F.Paste")
			(net "GND")
		)
		(pad "41" smd rect
			(at -1.533906 0.247904 90)
			(size 0.508 0.3556)
			(layers "F.Cu" "F.Mask" "F.Paste")
			(net "TP_PVDDQ_GHJ_PH1_GL_1")
		)
	)
)
